(kicad_pcb
	(version 20241229)
	(generator "pcbnew")
	(generator_version "9.0")
	(general
		(thickness 1.6296)
		(legacy_teardrops no)
	)
	(paper "A3")
	(title_block
		(title "Thunderbolt to 10GbE adapter")
		(date "2026-04-21")
		(rev "1.1.0")
		(company "Antmicro Ltd")
		(comment 1 "www.antmicro.com")
		(comment 9 "footprints 569-573 of 703")
	)
	(layers
		(0 "F.Cu" signal)
		(4 "In1.Cu" signal)
		(6 "In2.Cu" signal)
		(8 "In3.Cu" signal)
		(10 "In4.Cu" signal)
		(12 "In5.Cu" signal)
		(14 "In6.Cu" signal)
		(2 "B.Cu" signal)
		(9 "F.Adhes" user "F.Adhesive")
		(11 "B.Adhes" user "B.Adhesive")
		(13 "F.Paste" user)
		(15 "B.Paste" user)
		(5 "F.SilkS" user "F.Silkscreen")
		(7 "B.SilkS" user "B.Silkscreen")
		(1 "F.Mask" user)
		(3 "B.Mask" user)
		(17 "Dwgs.User" user "User.Drawings")
		(19 "Cmts.User" user "User.Comments")
		(21 "Eco1.User" user "User.Eco1")
		(23 "Eco2.User" user "User.Eco2")
		(25 "Edge.Cuts" user)
		(27 "Margin" user)
		(31 "F.CrtYd" user "F.Courtyard")
		(29 "B.CrtYd" user "B.Courtyard")
		(35 "F.Fab" user)
		(33 "B.Fab" user)
	)
	(footprint "antmicro-footprints:C_0402_1005Metric"
		(layer "B.Cu")
		(at 123.624999 123.950001 -90)
		(descr "Capacitor SMD 0402")
		(tags "capacitor SMD 0402")
		(property "Reference" "C70"
			(at -4.750001 -22.975001 90)
			(layer "B.SilkS")
			(effects
				(font
					(size 0.7 0.7)
					(thickness 0.15)
				)
				(justify mirror)
			)
		)
		(property "Value" "C_1u_0402"
			(at -1.022927 -2.155213 90)
			(layer "B.Fab")
			(effects
				(font
					(size 0.7 0.7)
					(thickness 0.15)
				)
				(justify left bottom mirror)
			)
		)
		(property "Datasheet" "https://product.tdk.com/en/search/capacitor/ceramic/mlcc/info?part_no=C1005X6S1A105K050BC"
			(at 0 0 90)
			(layer "B.Fab")
			(hide yes)
			(effects
				(font
					(size 1.27 1.27)
					(thickness 0.15)
				)
				(justify mirror)
			)
		)
		(property "Description" "SMD Multilayer Ceramic Capacitor, 1 µF, 10 V, 0402 [1005 Metric], ± 10%, X6S, C"
			(at 0 0 90)
			(layer "B.Fab")
			(hide yes)
			(effects
				(font
					(size 1.27 1.27)
					(thickness 0.15)
				)
				(justify mirror)
			)
		)
		(property "MPN" "C1005X6S1A105K050BC"
			(at 0 0 270)
			(unlocked yes)
			(layer "B.Fab")
			(hide yes)
			(effects
				(font
					(size 1 1)
					(thickness 0.15)
				)
				(justify mirror)
			)
		)
		(property "Manufacturer" "TDK"
			(at 0 0 270)
			(unlocked yes)
			(layer "B.Fab")
			(hide yes)
			(effects
				(font
					(size 1 1)
					(thickness 0.15)
				)
				(justify mirror)
			)
		)
		(property "License" "Apache-2.0"
			(at 0 0 270)
			(unlocked yes)
			(layer "B.Fab")
			(hide yes)
			(effects
				(font
					(size 1 1)
					(thickness 0.15)
				)
				(justify mirror)
			)
		)
		(property "Val" "1u"
			(at 0 0 270)
			(unlocked yes)
			(layer "B.Fab")
			(hide yes)
			(effects
				(font
					(size 1 1)
					(thickness 0.15)
				)
				(justify mirror)
			)
		)
		(property "Voltage" ""
			(at 0 0 270)
			(unlocked yes)
			(layer "B.Fab")
			(hide yes)
			(effects
				(font
					(size 1 1)
					(thickness 0.15)
				)
				(justify mirror)
			)
		)
		(property "Dielectric" ""
			(at 0 0 270)
			(unlocked yes)
			(layer "B.Fab")
			(hide yes)
			(effects
				(font
					(size 1 1)
					(thickness 0.15)
				)
				(justify mirror)
			)
		)
		(property "Author" "Antmicro"
			(at 0 0 270)
			(unlocked yes)
			(layer "B.Fab")
			(hide yes)
			(effects
				(font
					(size 1 1)
					(thickness 0.15)
				)
				(justify mirror)
			)
		)
		(sheetname "/TB Controller - Power/")
		(sheetfile "tb-power.kicad_sch")
		(attr smd)
		(fp_rect
			(start -0.925 0.47)
			(end 0.925 -0.47)
			(stroke
				(width 0.05)
				(type default)
			)
			(fill no)
			(layer "B.CrtYd")
		)
		(fp_line
			(start -0.494 0.25)
			(end 0.504 0.25)
			(stroke
				(width 0.15)
				(type solid)
			)
			(layer "B.Fab")
		)
		(fp_line
			(start 0.504 0.25)
			(end 0.504 -0.248)
			(stroke
				(width 0.15)
				(type solid)
			)
			(layer "B.Fab")
		)
		(fp_line
			(start -0.494 -0.248)
			(end -0.494 0.25)
			(stroke
				(width 0.15)
				(type solid)
			)
			(layer "B.Fab")
		)
		(fp_line
			(start 0.504 -0.248)
			(end -0.494 -0.248)
			(stroke
				(width 0.15)
				(type solid)
			)
			(layer "B.Fab")
		)
		(fp_text user "${REFERENCE}"
			(at -0.939 -4.599 90)
			(layer "B.Fab")
			(effects
				(font
					(size 0.7 0.7)
					(thickness 0.15)
				)
				(justify left bottom mirror)
			)
		)
		(fp_text user "License: Apache-2.0"
			(at -0.939 -5.799 90)
			(layer "B.Fab")
			(effects
				(font
					(size 0.7 0.7)
					(thickness 0.15)
				)
				(justify left bottom mirror)
			)
		)
		(fp_text user "Author: Antmicro"
			(at -0.939 -3.399 90)
			(layer "B.Fab")
			(effects
				(font
					(size 0.7 0.7)
					(thickness 0.15)
				)
				(justify left bottom mirror)
			)
		)
		(pad "1" smd roundrect
			(at -0.48 0 270)
			(size 0.59 0.64)
			(layers "B.Cu" "B.Mask" "B.Paste")
			(roundrect_rratio 0.25)
			(net 23 "GND")
			(pintype "passive")
		)
		(pad "2" smd roundrect
			(at 0.48 0 270)
			(size 0.59 0.64)
			(layers "B.Cu" "B.Mask" "B.Paste")
			(roundrect_rratio 0.25)
			(net 403 "Net-(C55-Pad2)")
			(pintype "passive")
		)
	)
	(footprint "antmicro-footprints:SOT-416"
		(layer "B.Cu")
		(at 178.5 73 -90)
		(descr "SOT-416")
		(tags "SOT-416")
		(property "Reference" "Q4"
			(at -0.75 1.3 90)
			(layer "B.SilkS")
			(effects
				(font
					(size 0.7 0.7)
					(thickness 0.15)
				)
				(justify left bottom mirror)
			)
		)
		(property "Value" "DTC014T_SOT-416"
			(at 0 -2 90)
			(layer "B.Fab")
			(effects
				(font
					(size 0.7 0.7)
					(thickness 0.15)
				)
				(justify left bottom mirror)
			)
		)
		(property "Datasheet" "https://www.rohm.com/datasheet?p=DTC014TEB&dist=Mouser&media=referral&source=mouser.com&campaign=Mouser"
			(at 0 0 90)
			(layer "B.Fab")
			(hide yes)
			(effects
				(font
					(size 1.27 1.27)
					(thickness 0.15)
				)
				(justify mirror)
			)
		)
		(property "Description" "Bipolar (BJT) Single Transistor with built-in base resistor, NPN, 50V, 100mA, 150mW, SOT-416FL, Surface Mount"
			(at 0 0 90)
			(layer "B.Fab")
			(hide yes)
			(effects
				(font
					(size 1.27 1.27)
					(thickness 0.15)
				)
				(justify mirror)
			)
		)
		(property "Manufacturer" "ROHM Semiconductor"
			(at 0 0 270)
			(unlocked yes)
			(layer "B.Fab")
			(hide yes)
			(effects
				(font
					(size 1 1)
					(thickness 0.15)
				)
				(justify mirror)
			)
		)
		(property "MPN" "DTC014TEBTL"
			(at 0 0 270)
			(unlocked yes)
			(layer "B.Fab")
			(hide yes)
			(effects
				(font
					(size 1 1)
					(thickness 0.15)
				)
				(justify mirror)
			)
		)
		(property "Author" "Antmicro"
			(at 0 0 270)
			(unlocked yes)
			(layer "B.Fab")
			(hide yes)
			(effects
				(font
					(size 1 1)
					(thickness 0.15)
				)
				(justify mirror)
			)
		)
		(property "License" "Apache-2.0"
			(at 0 0 270)
			(unlocked yes)
			(layer "B.Fab")
			(hide yes)
			(effects
				(font
					(size 1 1)
					(thickness 0.15)
				)
				(justify mirror)
			)
		)
		(sheetname "/X710 DCDC converters/")
		(sheetfile "DCDC_converters_X710.kicad_sch")
		(attr smd)
		(fp_line
			(start 0.508 0.9)
			(end -0.5 0.9)
			(stroke
				(width 0.15)
				(type solid)
			)
			(layer "B.SilkS")
		)
		(fp_line
			(start 0.508 0.9)
			(end 0.508 0.592)
			(stroke
				(width 0.15)
				(type solid)
			)
			(layer "B.SilkS")
		)
		(fp_line
			(start -0.5 0.15)
			(end -0.5 -0.15)
			(stroke
				(width 0.15)
				(type solid)
			)
			(layer "B.SilkS")
		)
		(fp_line
			(start 0.5 -0.9)
			(end 0.5 -0.7)
			(stroke
				(width 0.15)
				(type solid)
			)
			(layer "B.SilkS")
		)
		(fp_line
			(start 0.5 -0.9)
			(end -0.5 -0.9)
			(stroke
				(width 0.15)
				(type solid)
			)
			(layer "B.SilkS")
		)
		(fp_rect
			(start -1 1.05)
			(end 1 -1.05)
			(stroke
				(width 0.05)
				(type solid)
			)
			(fill no)
			(layer "B.CrtYd")
		)
		(fp_line
			(start -0.05 0.9)
			(end -0.45 0.5)
			(stroke
				(width 0.15)
				(type solid)
			)
			(layer "B.Fab")
		)
		(fp_rect
			(start 0.45 -0.9)
			(end -0.45 0.9)
			(stroke
				(width 0.15)
				(type solid)
			)
			(fill no)
			(layer "B.Fab")
		)
		(fp_text user "Author: Antmicro"
			(at -1 -4.602 90)
			(layer "B.Fab")
			(effects
				(font
					(size 0.7 0.7)
					(thickness 0.15)
				)
				(justify left bottom mirror)
			)
		)
		(fp_text user "License: Apache-2.0"
			(at -1 -5.802 90)
			(layer "B.Fab")
			(effects
				(font
					(size 0.7 0.7)
					(thickness 0.15)
				)
				(justify left bottom mirror)
			)
		)
		(fp_text user "${REFERENCE}"
			(at -1 -3.4 90)
			(layer "B.Fab")
			(effects
				(font
					(size 0.7 0.7)
					(thickness 0.15)
				)
				(justify left bottom mirror)
			)
		)
		(pad "1" smd rect
			(at -0.652 0.5 270)
			(size 0.6 0.5)
			(layers "B.Cu" "B.Mask" "B.Paste")
			(net 339 "/X710 DCDC converters/+1V0_OUT")
			(pinfunction "B")
			(pintype "input")
		)
		(pad "2" smd rect
			(at -0.652 -0.498 270)
			(size 0.6 0.5)
			(layers "B.Cu" "B.Mask" "B.Paste")
			(net 23 "GND")
			(pinfunction "E")
			(pintype "passive")
		)
		(pad "3" smd rect
			(at 0.65 0 270)
			(size 0.6 0.5)
			(layers "B.Cu" "B.Mask" "B.Paste")
			(net 430 "Net-(Q4-C)")
			(pinfunction "C")
			(pintype "passive")
		)
	)
	(footprint "antmicro-footprints:TP_SMD_0.75mm"
		(layer "B.Cu")
		(at 153.7 62.935117 -90)
		(property "Reference" "TP23"
			(at -3.135117 -0.3 90)
			(layer "B.SilkS")
			(effects
				(font
					(size 0.7 0.7)
					(thickness 0.15)
				)
				(justify left bottom mirror)
			)
		)
		(property "Value" "TP_0.75mm_SMD"
			(at 0 -1.2 90)
			(layer "B.Fab")
			(effects
				(font
					(size 0.7 0.7)
					(thickness 0.15)
				)
				(justify left bottom mirror)
			)
		)
		(property "Description" "SMT test point"
			(at 0 0 90)
			(layer "B.Fab")
			(hide yes)
			(effects
				(font
					(size 1.27 1.27)
					(thickness 0.15)
				)
				(justify mirror)
			)
		)
		(property "MPN" ""
			(at 0 0 270)
			(unlocked yes)
			(layer "B.Fab")
			(hide yes)
			(effects
				(font
					(size 1 1)
					(thickness 0.15)
				)
				(justify mirror)
			)
		)
		(property "Manufacturer" ""
			(at 0 0 270)
			(unlocked yes)
			(layer "B.Fab")
			(hide yes)
			(effects
				(font
					(size 1 1)
					(thickness 0.15)
				)
				(justify mirror)
			)
		)
		(property "Author" "Antmicro"
			(at 0 0 270)
			(unlocked yes)
			(layer "B.Fab")
			(hide yes)
			(effects
				(font
					(size 1 1)
					(thickness 0.15)
				)
				(justify mirror)
			)
		)
		(property "License" "Apache-2.0"
			(at 0 0 270)
			(unlocked yes)
			(layer "B.Fab")
			(hide yes)
			(effects
				(font
					(size 1 1)
					(thickness 0.15)
				)
				(justify mirror)
			)
		)
		(sheetname "/X710-AT2 Misc/")
		(sheetfile "x710-at2-mics.kicad_sch")
		(attr exclude_from_pos_files exclude_from_bom)
		(fp_circle
			(center 0 0)
			(end 0.475 0)
			(stroke
				(width 0.05)
				(type default)
			)
			(fill no)
			(layer "B.CrtYd")
		)
		(fp_text user "${REFERENCE}"
			(at -0.4 -2.7 90)
			(layer "B.Fab")
			(effects
				(font
					(size 0.7 0.7)
					(thickness 0.15)
				)
				(justify left bottom mirror)
			)
		)
		(fp_text user "Author: Antmicro"
			(at -0.4 -3.901 90)
			(layer "B.Fab")
			(effects
				(font
					(size 0.7 0.7)
					(thickness 0.15)
				)
				(justify left bottom mirror)
			)
		)
		(fp_text user "License: Apache-2.0"
			(at -0.4 -5.101 90)
			(layer "B.Fab")
			(effects
				(font
					(size 0.7 0.7)
					(thickness 0.15)
				)
				(justify left bottom mirror)
			)
		)
		(pad "1" smd circle
			(at 0 0 270)
			(size 0.75 0.75)
			(layers "B.Cu" "B.Mask")
			(net 144 "/X710-AT2 Misc/NCSI.REF_CLK")
			(pinfunction "1")
			(pintype "passive")
		)
	)
	(footprint "antmicro-footprints:R_0402_1005Metric"
		(layer "B.Cu")
		(at 138.450001 115.100002)
		(descr "Resistor SMD 0402")
		(tags "resistor SMD 0402")
		(property "Reference" "R48"
			(at 19.525001 -7.450001 180)
			(layer "B.SilkS")
			(effects
				(font
					(size 0.7 0.7)
					(thickness 0.15)
				)
				(justify mirror)
			)
		)
		(property "Value" "R_1M_0402"
			(at -1.011843 -1.772047 180)
			(layer "B.Fab")
			(effects
				(font
					(size 0.7 0.7)
					(thickness 0.15)
				)
				(justify left bottom mirror)
			)
		)
		(property "Datasheet" "https://www.bourns.com/docs/product-datasheets/cr.pdf"
			(at 0 0 180)
			(layer "B.Fab")
			(hide yes)
			(effects
				(font
					(size 1.27 1.27)
					(thickness 0.15)
				)
				(justify mirror)
			)
		)
		(property "Description" "SMD Chip Resistor, 1 Mohm, ± 1%, 62.5 mW, 0402 [1005 Metric], Thick Film, General Purpose"
			(at 0 0 180)
			(layer "B.Fab")
			(hide yes)
			(effects
				(font
					(size 1.27 1.27)
					(thickness 0.15)
				)
				(justify mirror)
			)
		)
		(property "MPN" "CR0402-FX-1004GLF"
			(at 0 0 0)
			(unlocked yes)
			(layer "B.Fab")
			(hide yes)
			(effects
				(font
					(size 1 1)
					(thickness 0.15)
				)
				(justify mirror)
			)
		)
		(property "Manufacturer" "Bourns"
			(at 0 0 0)
			(unlocked yes)
			(layer "B.Fab")
			(hide yes)
			(effects
				(font
					(size 1 1)
					(thickness 0.15)
				)
				(justify mirror)
			)
		)
		(property "License" "Apache-2.0"
			(at 0 0 0)
			(unlocked yes)
			(layer "B.Fab")
			(hide yes)
			(effects
				(font
					(size 1 1)
					(thickness 0.15)
				)
				(justify mirror)
			)
		)
		(property "Val" "1M"
			(at 0 0 0)
			(unlocked yes)
			(layer "B.Fab")
			(hide yes)
			(effects
				(font
					(size 1 1)
					(thickness 0.15)
				)
				(justify mirror)
			)
		)
		(property "Tolerance" "1%"
			(at 0 0 0)
			(unlocked yes)
			(layer "B.Fab")
			(hide yes)
			(effects
				(font
					(size 1 1)
					(thickness 0.15)
				)
				(justify mirror)
			)
		)
		(property "Author" "Antmicro"
			(at 0 0 0)
			(unlocked yes)
			(layer "B.Fab")
			(hide yes)
			(effects
				(font
					(size 1 1)
					(thickness 0.15)
				)
				(justify mirror)
			)
		)
		(sheetname "/TB Controller/")
		(sheetfile "tb.kicad_sch")
		(attr smd)
		(fp_rect
			(start -0.925 0.47)
			(end 0.925 -0.47)
			(stroke
				(width 0.05)
				(type default)
			)
			(fill no)
			(layer "B.CrtYd")
		)
		(fp_rect
			(start -0.5 0.25)
			(end 0.5 -0.25)
			(stroke
				(width 0.15)
				(type solid)
			)
			(fill no)
			(layer "B.Fab")
		)
		(fp_text user "${REFERENCE}"
			(at -0.95 -3.168 180)
			(layer "B.Fab")
			(effects
				(font
					(size 0.7 0.7)
					(thickness 0.15)
				)
				(justify left bottom mirror)
			)
		)
		(fp_text user "Author: Antmicro"
			(at -0.95 -4.169 180)
			(layer "B.Fab")
			(effects
				(font
					(size 0.7 0.7)
					(thickness 0.15)
				)
				(justify left bottom mirror)
			)
		)
		(fp_text user "License: Apache-2.0"
			(at -0.95 -5.169 180)
			(layer "B.Fab")
			(effects
				(font
					(size 0.7 0.7)
					(thickness 0.15)
				)
				(justify left bottom mirror)
			)
		)
		(pad "1" smd roundrect
			(at -0.48 0)
			(size 0.59 0.64)
			(layers "B.Cu" "B.Mask" "B.Paste")
			(roundrect_rratio 0.25)
			(net 191 "Net-(U4C-GPIO_8)")
			(pintype "passive")
		)
		(pad "2" smd roundrect
			(at 0.48 0)
			(size 0.59 0.64)
			(layers "B.Cu" "B.Mask" "B.Paste")
			(roundrect_rratio 0.25)
			(net 23 "GND")
			(pintype "passive")
		)
	)
	(footprint "antmicro-footprints:C_0402_1005Metric"
		(layer "B.Cu")
		(at 147.481865 81.260116 180)
		(descr "Capacitor SMD 0402")
		(tags "capacitor SMD 0402")
		(property "Reference" "C238"
			(at -18.618135 -9.464883 0)
			(layer "B.SilkS")
			(effects
				(font
					(size 0.7 0.7)
					(thickness 0.15)
				)
				(justify mirror)
			)
		)
		(property "Value" "C_1u_25V_0402"
			(at -1.022927 -2.155213 0)
			(layer "B.Fab")
			(effects
				(font
					(size 0.7 0.7)
					(thickness 0.15)
				)
				(justify left bottom mirror)
			)
		)
		(property "Datasheet" "https://www.murata.com/products/productdetail?partno=GRM155R61E105KE11%23"
			(at 0 0 0)
			(layer "B.Fab")
			(hide yes)
			(effects
				(font
					(size 1.27 1.27)
					(thickness 0.15)
				)
				(justify mirror)
			)
		)
		(property "Description" "SMD Multilayer Ceramic Capacitor, 1 µF, 25 V, 0402 [1005 Metric], ± 10%, X5R, GRM Series"
			(at 0 0 0)
			(layer "B.Fab")
			(hide yes)
			(effects
				(font
					(size 1.27 1.27)
					(thickness 0.15)
				)
				(justify mirror)
			)
		)
		(property "MPN" "GRM155R61E105KE11J"
			(at 0 0 180)
			(unlocked yes)
			(layer "B.Fab")
			(hide yes)
			(effects
				(font
					(size 1 1)
					(thickness 0.15)
				)
				(justify mirror)
			)
		)
		(property "Manufacturer" "Murata"
			(at 0 0 180)
			(unlocked yes)
			(layer "B.Fab")
			(hide yes)
			(effects
				(font
					(size 1 1)
					(thickness 0.15)
				)
				(justify mirror)
			)
		)
		(property "License" "Apache-2.0"
			(at 0 0 180)
			(unlocked yes)
			(layer "B.Fab")
			(hide yes)
			(effects
				(font
					(size 1 1)
					(thickness 0.15)
				)
				(justify mirror)
			)
		)
		(property "Author" "Antmicro"
			(at 0 0 180)
			(unlocked yes)
			(layer "B.Fab")
			(hide yes)
			(effects
				(font
					(size 1 1)
					(thickness 0.15)
				)
				(justify mirror)
			)
		)
		(property "Val" "1u"
			(at 0 0 180)
			(unlocked yes)
			(layer "B.Fab")
			(hide yes)
			(effects
				(font
					(size 1 1)
					(thickness 0.15)
				)
				(justify mirror)
			)
		)
		(property "Voltage" "25V"
			(at 0 0 180)
			(unlocked yes)
			(layer "B.Fab")
			(hide yes)
			(effects
				(font
					(size 1 1)
					(thickness 0.15)
				)
				(justify mirror)
			)
		)
		(property "Dielectric" "X5R"
			(at 0 0 180)
			(unlocked yes)
			(layer "B.Fab")
			(hide yes)
			(effects
				(font
					(size 1 1)
					(thickness 0.15)
				)
				(justify mirror)
			)
		)
		(sheetname "/X710-AT2 power/")
		(sheetfile "x710-at2-power.kicad_sch")
		(attr smd)
		(fp_rect
			(start -0.925 0.47)
			(end 0.925 -0.47)
			(stroke
				(width 0.05)
				(type default)
			)
			(fill no)
			(layer "B.CrtYd")
		)
		(fp_line
			(start 0.504 0.25)
			(end 0.504 -0.248)
			(stroke
				(width 0.15)
				(type solid)
			)
			(layer "B.Fab")
		)
		(fp_line
			(start 0.504 -0.248)
			(end -0.494 -0.248)
			(stroke
				(width 0.15)
				(type solid)
			)
			(layer "B.Fab")
		)
		(fp_line
			(start -0.494 0.25)
			(end 0.504 0.25)
			(stroke
				(width 0.15)
				(type solid)
			)
			(layer "B.Fab")
		)
		(fp_line
			(start -0.494 -0.248)
			(end -0.494 0.25)
			(stroke
				(width 0.15)
				(type solid)
			)
			(layer "B.Fab")
		)
		(fp_text user "${REFERENCE}"
			(at -0.939 -4.599 0)
			(layer "B.Fab")
			(effects
				(font
					(size 0.7 0.7)
					(thickness 0.15)
				)
				(justify left bottom mirror)
			)
		)
		(fp_text user "License: Apache-2.0"
			(at -0.939 -5.799 0)
			(layer "B.Fab")
			(effects
				(font
					(size 0.7 0.7)
					(thickness 0.15)
				)
				(justify left bottom mirror)
			)
		)
		(fp_text user "Author: Antmicro"
			(at -0.939 -3.399 0)
			(layer "B.Fab")
			(effects
				(font
					(size 0.7 0.7)
					(thickness 0.15)
				)
				(justify left bottom mirror)
			)
		)
		(pad "1" smd roundrect
			(at -0.48 0 180)
			(size 0.59 0.64)
			(layers "B.Cu" "B.Mask" "B.Paste")
			(roundrect_rratio 0.25)
			(net 23 "GND")
			(pintype "passive")
		)
		(pad "2" smd roundrect
			(at 0.48 0 180)
			(size 0.59 0.64)
			(layers "B.Cu" "B.Mask" "B.Paste")
			(roundrect_rratio 0.25)
			(net 7 "+3V3")
			(pintype "passive")
		)
	)
)
